# BASEBOARD_FAB2 (Tioga Pass) — schematic netlist excerpt (pin names and nets, part order shuffled) for the footprints in the layout excerpt that follows; sources: Cadence DE-HDL packaged netlist, KiCad conversion of Wiwynn_Tioga_Pass_MB.brd

C3P6  CAP  1000PF 50V 10% X7R  pkg 0402LF  page 211 : A = PWRGD_PVCCIO_CPU0_R ; B = GND
C6N9  CAPP  470UF 2.5V 20% ALUM  pkg 3018  page 203 : A = PVCCIN_CPU0 ; B = GND

Q7E4  FET_N  2N7002 FET  pkg SOT23LF  page 95
  GATE  = FM_THROTTLE_R_N
  SRC  = GND
  DRN  = FM_SYS_THROTTLE_LVC3

(kicad_pcb
	(version 20260206)
	(generator "pcbnew")
	(generator_version "10.0")
	(general
		(thickness 1.6)
		(legacy_teardrops no)
	)
	(paper "A4")
	(title_block
		(title "Wiwynn_Tioga_Pass_MB.brd")
		(comment 1 "Tioga Pass / footprints 3093-3095 of 4770")
	)
	(layers
		(0 "F.Cu" signal "TOP")
		(4 "In1.Cu" signal "L2GND")
		(6 "In2.Cu" signal "L3")
		(8 "In3.Cu" signal "L4GND")
		(10 "In4.Cu" signal "L5")
		(12 "In5.Cu" signal "L6GND")
		(14 "In6.Cu" signal "L7VCC")
		(16 "In7.Cu" signal "L8VCC")
		(18 "In8.Cu" signal "L9GND")
		(20 "In9.Cu" signal "L10")
		(22 "In10.Cu" signal "L11GND")
		(24 "In11.Cu" signal "L12")
		(26 "In12.Cu" signal "L13GND")
		(2 "B.Cu" signal "BOTTOM")
		(9 "F.Adhes" user "F.Adhesive")
		(11 "B.Adhes" user "B.Adhesive")
		(13 "F.Paste" user "Package Geometry/Pastemask Top")
		(15 "B.Paste" user "Package Geometry/Pastemask Bottom")
		(5 "F.SilkS" user "Ref Des/Silkscreen Top")
		(7 "B.SilkS" user "Ref Des/Silkscreen Bottom")
		(1 "F.Mask" user "Board Geometry/Soldermask Top")
		(3 "B.Mask" user "Board Geometry/Soldermask Bottom")
		(17 "Dwgs.User" user "User.Drawings")
		(19 "Cmts.User" user "User.Comments")
		(21 "Eco1.User" user "User.Eco1")
		(23 "Eco2.User" user "User.Eco2")
		(25 "Edge.Cuts" user "Board Geometry/Outline")
		(27 "Margin" user)
		(31 "F.CrtYd" user "Package Geometry/Place Bound Top")
		(29 "B.CrtYd" user "Package Geometry/Place Bound Bottom")
		(35 "F.Fab" user "Ref Des/Assembly Top")
		(33 "B.Fab" user "Ref Des/Assembly Bottom")
	)
	(footprint ""
		(layer "B.Cu")
		(at 385.774692 -44.215812)
		(property "Reference" "Q7E4"
			(at -0.22733 -3.73888 90)
			(unlocked yes)
			(layer "B.SilkS")
			(effects
				(font
					(size 0.7874 0.5842)
					(thickness 0.1524)
				)
				(justify left mirror)
			)
		)
		(property "Value" ""
			(at 0 0 0)
			(layer "B.Fab")
			(effects
				(font
					(size 1.27 1.27)
				)
				(justify mirror)
			)
		)
		(duplicate_pad_numbers_are_jumpers no)
		(fp_line
			(start -1.778 -0.5715)
			(end -1.778 0.3175)
			(stroke
				(width 0.1524)
				(type default)
			)
			(layer "B.SilkS")
		)
		(fp_line
			(start -1.778 2.4765)
			(end -1.778 1.5875)
			(stroke
				(width 0.1524)
				(type default)
			)
			(layer "B.SilkS")
		)
		(fp_line
			(start -0.9525 -0.5715)
			(end -1.778 -0.5715)
			(stroke
				(width 0.1524)
				(type default)
			)
			(layer "B.SilkS")
		)
		(fp_line
			(start -0.9525 2.4765)
			(end -1.778 2.4765)
			(stroke
				(width 0.1524)
				(type default)
			)
			(layer "B.SilkS")
		)
		(fp_line
			(start -0.381 0.635)
			(end -0.381 1.27)
			(stroke
				(width 0.1524)
				(type default)
			)
			(layer "B.SilkS")
		)
		(fp_circle
			(center 0.9525 -0.9271)
			(end 1.0795 -0.9271)
			(stroke
				(width 0.254)
				(type default)
			)
			(fill no)
			(layer "B.SilkS")
		)
		(fp_poly
			(pts
				(xy -1.778 2.4765) (xy -0.381 2.4765) (xy -0.381 -0.5715) (xy -1.778 -0.5715)
			)
			(stroke
				(width 0)
				(type default)
			)
			(fill no)
			(layer "B.CrtYd")
		)
		(fp_line
			(start -1.778 -0.5715)
			(end -0.381 -0.5715)
			(stroke
				(width 0.1)
				(type default)
			)
			(layer "B.Fab")
		)
		(fp_line
			(start -1.778 2.4765)
			(end -1.778 -0.5715)
			(stroke
				(width 0.1)
				(type default)
			)
			(layer "B.Fab")
		)
		(fp_line
			(start -0.381 -0.5715)
			(end -0.381 2.4765)
			(stroke
				(width 0.1)
				(type default)
			)
			(layer "B.Fab")
		)
		(fp_line
			(start -0.381 2.4765)
			(end -1.778 2.4765)
			(stroke
				(width 0.1)
				(type default)
			)
			(layer "B.Fab")
		)
		(fp_circle
			(center 0.9525 -0.9271)
			(end 1.0795 -0.9271)
			(stroke
				(width 0.254)
				(type default)
			)
			(fill no)
			(layer "B.Fab")
		)
		(pad "1" smd rect
			(at 0 0 180)
			(size 1.143 0.508)
			(layers "B.Cu" "B.Mask" "B.Paste")
			(net "FM_THROTTLE_R_N")
		)
		(pad "2" smd rect
			(at 0 1.905 180)
			(size 1.143 0.508)
			(layers "B.Cu" "B.Mask" "B.Paste")
			(net "GND")
		)
		(pad "3" smd rect
			(at -2.159 0.9525 180)
			(size 1.143 0.508)
			(layers "B.Cu" "B.Mask" "B.Paste")
			(net "FM_SYS_THROTTLE_LVC3")
		)
	)
	(footprint ""
		(layer "B.Cu")
		(at 342.9 -83.566)
		(property "Reference" "C3P6"
			(at 0 0 0)
			(layer "B.SilkS")
			(hide yes)
			(effects
				(font
					(size 1.27 1.27)
				)
				(justify mirror)
			)
		)
		(property "Value" ""
			(at 0 0 0)
			(layer "B.Fab")
			(effects
				(font
					(size 1.27 1.27)
				)
				(justify mirror)
			)
		)
		(duplicate_pad_numbers_are_jumpers no)
		(fp_poly
			(pts
				(xy -0.3048 -0.1016) (xy -0.3048 0.9906) (xy 0.3048 0.9906) (xy 0.3048 -0.1016)
			)
			(stroke
				(width 0)
				(type default)
			)
			(fill no)
			(layer "B.CrtYd")
		)
		(fp_line
			(start -0.3048 -0.1016)
			(end 0.3048 -0.1016)
			(stroke
				(width 0.1)
				(type default)
			)
			(layer "B.Fab")
		)
		(fp_line
			(start -0.3048 0.9906)
			(end -0.3048 -0.1016)
			(stroke
				(width 0.1)
				(type default)
			)
			(layer "B.Fab")
		)
		(fp_line
			(start 0.3048 -0.1016)
			(end 0.3048 0.9906)
			(stroke
				(width 0.1)
				(type default)
			)
			(layer "B.Fab")
		)
		(fp_line
			(start 0.3048 0.9906)
			(end -0.3048 0.9906)
			(stroke
				(width 0.1)
				(type default)
			)
			(layer "B.Fab")
		)
		(pad "1" smd rect
			(at 0 0 180)
			(size 0.508 0.508)
			(layers "B.Cu" "B.Mask" "B.Paste")
			(net "PWRGD_PVCCIO_CPU0_R")
		)
		(pad "2" smd rect
			(at 0 0.889 180)
			(size 0.508 0.508)
			(layers "B.Cu" "B.Mask" "B.Paste")
			(net "GND")
		)
		(zone
			(layer "B.Cu")
			(hatch none 0.5)
			(connect_pads
				(clearance 0)
			)
			(min_thickness 0.25)
			(keepout
				(tracks allowed)
				(vias not_allowed)
				(pads allowed)
				(copperpour not_allowed)
				(footprints allowed)
			)
			(placement
				(enabled no)
				(sheetname "")
			)
			(fill
				(thermal_gap 0.5)
				(thermal_bridge_width 0.5)
				(island_removal_mode 0)
			)
			(polygon
				(pts
					(xy 343.154 -83.312) (xy 342.646 -83.312) (xy 342.646 -82.931) (xy 343.154 -82.931)
				)
			)
		)
		(zone
			(layer "B.Cu")
			(hatch none 0.5)
			(connect_pads
				(clearance 0)
			)
			(min_thickness 0.25)
			(keepout
				(tracks not_allowed)
				(vias allowed)
				(pads allowed)
				(copperpour not_allowed)
				(footprints allowed)
			)
			(placement
				(enabled no)
				(sheetname "")
			)
			(fill
				(thermal_gap 0.5)
				(thermal_bridge_width 0.5)
				(island_removal_mode 0)
			)
			(polygon
				(pts
					(xy 343.154 -82.931) (xy 342.646 -82.931) (xy 342.646 -83.312) (xy 343.154 -83.312)
				)
			)
		)
	)
	(footprint ""
		(layer "B.Cu")
		(at 210.847432 -89.6112 -90)
		(property "Reference" "C6N9"
			(at -1.54813 -3.655568 0)
			(unlocked yes)
			(layer "B.SilkS")
			(effects
				(font
					(size 0.7874 0.5842)
					(thickness 0.1524)
				)
				(justify mirror)
			)
		)
		(property "Value" ""
			(at 0 0 90)
			(layer "B.Fab")
			(effects
				(font
					(size 1.27 1.27)
				)
				(justify mirror)
			)
		)
		(duplicate_pad_numbers_are_jumpers no)
		(fp_line
			(start -2.286 7.366)
			(end -1.600708 7.366)
			(stroke
				(width 0.1524)
				(type default)
			)
			(layer "B.SilkS")
		)
		(fp_line
			(start -2.286 7.366)
			(end -2.286 1.63195)
			(stroke
				(width 0.1524)
				(type default)
			)
			(layer "B.SilkS")
		)
		(fp_line
			(start 2.286 7.366)
			(end 1.60147 7.366)
			(stroke
				(width 0.1524)
				(type default)
			)
			(layer "B.SilkS")
		)
		(fp_line
			(start 2.286 7.366)
			(end 2.286 1.632712)
			(stroke
				(width 0.1524)
				(type default)
			)
			(layer "B.SilkS")
		)
		(fp_line
			(start -2.504948 1.633728)
			(end -1.6002 1.633728)
			(stroke
				(width 0.1524)
				(type default)
			)
			(layer "B.SilkS")
		)
		(fp_line
			(start 2.563114 1.633728)
			(end 1.6002 1.633728)
			(stroke
				(width 0.1524)
				(type default)
			)
			(layer "B.SilkS")
		)
		(fp_line
			(start -2.504948 -1.616456)
			(end -2.504948 1.633728)
			(stroke
				(width 0.1524)
				(type default)
			)
			(layer "B.SilkS")
		)
		(fp_line
			(start -1.6002 -1.616456)
			(end -2.504948 -1.616456)
			(stroke
				(width 0.1524)
				(type default)
			)
			(layer "B.SilkS")
		)
		(fp_line
			(start 1.6002 -1.616456)
			(end 2.563114 -1.616456)
			(stroke
				(width 0.1524)
				(type default)
			)
			(layer "B.SilkS")
		)
		(fp_line
			(start 2.563114 -1.616456)
			(end 2.563114 1.633728)
			(stroke
				(width 0.1524)
				(type default)
			)
			(layer "B.SilkS")
		)
		(fp_rect
			(start 2.286 7.366)
			(end -2.286 -0.254)
			(stroke
				(width 0)
				(type default)
			)
			(fill no)
			(layer "B.CrtYd")
		)
		(fp_line
			(start -2.286 7.366)
			(end 2.286 7.366)
			(stroke
				(width 0.1)
				(type default)
			)
			(layer "B.Fab")
		)
		(fp_line
			(start 2.286 7.366)
			(end 2.286 -0.254)
			(stroke
				(width 0.1)
				(type default)
			)
			(layer "B.Fab")
		)
		(fp_line
			(start -2.286 -0.254)
			(end -2.286 7.366)
			(stroke
				(width 0.1)
				(type default)
			)
			(layer "B.Fab")
		)
		(fp_line
			(start 2.286 -0.254)
			(end -2.286 -0.254)
			(stroke
				(width 0.1)
				(type default)
			)
			(layer "B.Fab")
		)
		(pad "1" smd rect
			(at 0 0 90)
			(size 2.54 3.048)
			(layers "B.Cu" "B.Mask" "B.Paste")
			(net "PVCCIN_CPU0")
		)
		(pad "2" smd rect
			(at 0 7.112 90)
			(size 2.54 3.048)
			(layers "B.Cu" "B.Mask" "B.Paste")
			(net "GND")
		)
	)
)
